(kicad_pcb
	(version 20260206)
	(generator "pcbnew")
	(generator_version "10.0")
	(general
		(thickness 1.6)
		(legacy_teardrops no)
	)
	(paper "A4")
	(title_block
		(title "panther-plus-userver — 13130-1b_20150205.brd")
		(comment 1 "Honey Badger (Wiwynn) / footprints 443-450 of 1509")
	)
	(layers
		(0 "F.Cu" signal "TOP")
		(4 "In1.Cu" signal "L2")
		(6 "In2.Cu" signal "L3")
		(8 "In3.Cu" signal "L4")
		(10 "In4.Cu" signal "L5")
		(12 "In5.Cu" signal "L6")
		(14 "In6.Cu" signal "L7")
		(16 "In7.Cu" signal "L8")
		(18 "In8.Cu" signal "L9")
		(20 "In9.Cu" signal "L10")
		(22 "In10.Cu" signal "L11")
		(2 "B.Cu" signal "BOTTOM")
		(9 "F.Adhes" user "F.Adhesive")
		(11 "B.Adhes" user "B.Adhesive")
		(13 "F.Paste" user "Package Geometry/Pastemask Top")
		(15 "B.Paste" user "Package Geometry/Pastemask Bottom")
		(5 "F.SilkS" user "Ref Des/Silkscreen Top")
		(7 "B.SilkS" user "Ref Des/Silkscreen Bottom")
		(1 "F.Mask" user "Board Geometry/Soldermask Top")
		(3 "B.Mask" user "Board Geometry/Soldermask Bottom")
		(17 "Dwgs.User" user "User.Drawings")
		(19 "Cmts.User" user "User.Comments")
		(21 "Eco1.User" user "User.Eco1")
		(23 "Eco2.User" user "User.Eco2")
		(25 "Edge.Cuts" user "Board Geometry/Outline")
		(27 "Margin" user)
		(31 "F.CrtYd" user "Package Geometry/Place Bound Top")
		(29 "B.CrtYd" user "Package Geometry/Place Bound Bottom")
		(35 "F.Fab" user "Ref Des/Assembly Top")
		(33 "B.Fab" user "Ref Des/Assembly Bottom")
	)
	(footprint ""
		(layer "F.Cu")
		(at 189.611 -40.259 90)
		(property "Reference" "PR119"
			(at 0 0 90)
			(layer "F.SilkS")
			(hide yes)
			(effects
				(font
					(size 1.27 1.27)
				)
			)
		)
		(property "Value" "0R2J-2-GP"
			(at 1.7907 -1.1176 90)
			(unlocked yes)
			(layer "F.Fab")
			(hide yes)
			(effects
				(font
					(size 1.016 1.016)
					(thickness 0.1524)
				)
			)
		)
		(property "Device Type" "R402H16"
			(at 1.7907 -2.6416 90)
			(unlocked yes)
			(layer "F.Fab")
			(hide yes)
			(effects
				(font
					(size 1.016 1.016)
					(thickness 0.1524)
				)
			)
		)
		(duplicate_pad_numbers_are_jumpers no)
		(fp_rect
			(start -0.381 0.8382)
			(end 0.381 -0.8382)
			(stroke
				(width 0)
				(type default)
			)
			(fill no)
			(layer "F.CrtYd")
		)
		(fp_rect
			(start -0.381 0.8382)
			(end 0.381 -0.8382)
			(stroke
				(width 0)
				(type default)
			)
			(fill no)
			(layer "F.Fab")
		)
		(pad "1" smd custom
			(at 0 -0.4318 90)
			(size 0.127 0.127)
			(layers "F.Cu" "F.Mask" "F.Paste")
			(net "VR_PVDDR_A_VAUTO")
			(options
				(clearance outline)
				(anchor circle)
			)
			(primitives
				(gr_poly
					(pts
						(arc
							(start -0.2032 -0.2794)
							(mid -0.239121 -0.264521)
							(end -0.254 -0.2286)
						)
						(arc
							(start -0.254 0.2286)
							(mid -0.239121 0.264521)
							(end -0.2032 0.2794)
						)
						(arc
							(start 0.2032 0.2794)
							(mid 0.239121 0.264521)
							(end 0.254 0.2286)
						)
						(arc
							(start 0.254 -0.2286)
							(mid 0.239121 -0.264521)
							(end 0.2032 -0.2794)
						)
					)
					(width 0)
					(fill yes)
				)
			)
		)
		(pad "2" smd custom
			(at 0 0.4318 90)
			(size 0.127 0.127)
			(layers "F.Cu" "F.Mask" "F.Paste")
			(net "GND")
			(options
				(clearance outline)
				(anchor circle)
			)
			(primitives
				(gr_poly
					(pts
						(arc
							(start -0.2032 -0.2794)
							(mid -0.239121 -0.264521)
							(end -0.254 -0.2286)
						)
						(arc
							(start -0.254 0.2286)
							(mid -0.239121 0.264521)
							(end -0.2032 0.2794)
						)
						(arc
							(start 0.2032 0.2794)
							(mid 0.239121 0.264521)
							(end 0.254 0.2286)
						)
						(arc
							(start 0.254 -0.2286)
							(mid 0.239121 -0.264521)
							(end 0.2032 -0.2794)
						)
					)
					(width 0)
					(fill yes)
				)
			)
		)
	)
	(footprint ""
		(layer "F.Cu")
		(at 31.369 -30.734 -90)
		(property "Reference" "R272"
			(at 0 0 270)
			(layer "F.SilkS")
			(hide yes)
			(effects
				(font
					(size 1.27 1.27)
				)
			)
		)
		(property "Value" "1KR3J-L1-GP"
			(at -0.0254 -2.5146 270)
			(unlocked yes)
			(layer "F.Fab")
			(hide yes)
			(effects
				(font
					(size 1.016 1.016)
					(thickness 0.1524)
				)
			)
		)
		(property "Device Type" "R603H22"
			(at -0.0254 -4.0386 270)
			(unlocked yes)
			(layer "F.Fab")
			(hide yes)
			(effects
				(font
					(size 1.016 1.016)
					(thickness 0.1524)
				)
			)
		)
		(duplicate_pad_numbers_are_jumpers no)
		(fp_line
			(start -0.2032 0)
			(end -0.4191 0)
			(stroke
				(width 0.2032)
				(type default)
			)
			(layer "F.SilkS")
		)
		(fp_line
			(start 0.4318 0)
			(end 0.2032 0)
			(stroke
				(width 0.2032)
				(type default)
			)
			(layer "F.SilkS")
		)
		(fp_rect
			(start -0.635 1.1811)
			(end 0.635 -1.1811)
			(stroke
				(width 0)
				(type default)
			)
			(fill no)
			(layer "F.CrtYd")
		)
		(fp_rect
			(start -0.635 1.1811)
			(end 0.635 -1.1811)
			(stroke
				(width 0)
				(type default)
			)
			(fill no)
			(layer "F.Fab")
		)
		(pad "1" smd custom
			(at 0 -0.6604 270)
			(size 0.19685 0.19685)
			(layers "F.Cu" "F.Mask" "F.Paste")
			(net "XDP_CPU_R_RESET#")
			(options
				(clearance outline)
				(anchor circle)
			)
			(primitives
				(gr_poly
					(pts
						(arc
							(start 0.508 -0.2921)
							(mid 0.478242 -0.363942)
							(end 0.4064 -0.3937)
						)
						(arc
							(start -0.4064 -0.3937)
							(mid -0.478242 -0.363942)
							(end -0.508 -0.2921)
						)
						(arc
							(start -0.508 0.2921)
							(mid -0.478242 0.363942)
							(end -0.4064 0.3937)
						)
						(arc
							(start 0.4064 0.3937)
							(mid 0.478242 0.363942)
							(end 0.508 0.2921)
						)
					)
					(width 0)
					(fill yes)
				)
			)
		)
		(pad "2" smd custom
			(at 0 0.6604 270)
			(size 0.19685 0.19685)
			(layers "F.Cu" "F.Mask" "F.Paste")
			(net "XDP_CPU_RESET#")
			(options
				(clearance outline)
				(anchor circle)
			)
			(primitives
				(gr_poly
					(pts
						(arc
							(start 0.508 -0.2921)
							(mid 0.478242 -0.363942)
							(end 0.4064 -0.3937)
						)
						(arc
							(start -0.4064 -0.3937)
							(mid -0.478242 -0.363942)
							(end -0.508 -0.2921)
						)
						(arc
							(start -0.508 0.2921)
							(mid -0.478242 0.363942)
							(end -0.4064 0.3937)
						)
						(arc
							(start 0.4064 0.3937)
							(mid 0.478242 0.363942)
							(end 0.508 0.2921)
						)
					)
					(width 0)
					(fill yes)
				)
			)
		)
	)
	(footprint ""
		(layer "F.Cu")
		(at 46.863 -16.0782 180)
		(property "Reference" "R359"
			(at 0 0 180)
			(layer "F.SilkS")
			(hide yes)
			(effects
				(font
					(size 1.27 1.27)
				)
			)
		)
		(property "Value" "4K7R2F-GP"
			(at 0.064008 -3.993896 180)
			(unlocked yes)
			(layer "F.Fab")
			(hide yes)
			(effects
				(font
					(size 1.016 1.016)
					(thickness 0.1524)
				)
			)
		)
		(property "Device Type" "R402H16"
			(at 0.064008 -5.517896 180)
			(unlocked yes)
			(layer "F.Fab")
			(hide yes)
			(effects
				(font
					(size 1.016 1.016)
					(thickness 0.1524)
				)
			)
		)
		(duplicate_pad_numbers_are_jumpers no)
		(fp_rect
			(start -0.381 0.8382)
			(end 0.381 -0.8382)
			(stroke
				(width 0)
				(type default)
			)
			(fill no)
			(layer "F.CrtYd")
		)
		(fp_rect
			(start -0.381 0.8382)
			(end 0.381 -0.8382)
			(stroke
				(width 0)
				(type default)
			)
			(fill no)
			(layer "F.Fab")
		)
		(pad "1" smd custom
			(at 0 -0.4318 180)
			(size 0.127 0.127)
			(layers "F.Cu" "F.Mask" "F.Paste")
			(net "P3V3")
			(options
				(clearance outline)
				(anchor circle)
			)
			(primitives
				(gr_poly
					(pts
						(arc
							(start -0.2032 -0.2794)
							(mid -0.239121 -0.264521)
							(end -0.254 -0.2286)
						)
						(arc
							(start -0.254 0.2286)
							(mid -0.239121 0.264521)
							(end -0.2032 0.2794)
						)
						(arc
							(start 0.2032 0.2794)
							(mid 0.239121 0.264521)
							(end 0.254 0.2286)
						)
						(arc
							(start 0.254 -0.2286)
							(mid 0.239121 -0.264521)
							(end 0.2032 -0.2794)
						)
					)
					(width 0)
					(fill yes)
				)
			)
		)
		(pad "2" smd custom
			(at 0 0.4318 180)
			(size 0.127 0.127)
			(layers "F.Cu" "F.Mask" "F.Paste")
			(net "CLKBUFF_OE2#")
			(options
				(clearance outline)
				(anchor circle)
			)
			(primitives
				(gr_poly
					(pts
						(arc
							(start -0.2032 -0.2794)
							(mid -0.239121 -0.264521)
							(end -0.254 -0.2286)
						)
						(arc
							(start -0.254 0.2286)
							(mid -0.239121 0.264521)
							(end -0.2032 0.2794)
						)
						(arc
							(start 0.2032 0.2794)
							(mid 0.239121 0.264521)
							(end 0.254 0.2286)
						)
						(arc
							(start 0.254 -0.2286)
							(mid 0.239121 -0.264521)
							(end 0.2032 -0.2794)
						)
					)
					(width 0)
					(fill yes)
				)
			)
		)
	)
	(footprint ""
		(layer "F.Cu")
		(at 51.816 -50.8)
		(property "Reference" "PR153"
			(at 0 0 0)
			(layer "F.SilkS")
			(hide yes)
			(effects
				(font
					(size 1.27 1.27)
				)
			)
		)
		(property "Value" "0R3J-6-GP"
			(at -0.0254 -2.0193 0)
			(unlocked yes)
			(layer "F.Fab")
			(hide yes)
			(effects
				(font
					(size 1.016 1.016)
					(thickness 0.1524)
				)
			)
		)
		(property "Device Type" "R603H22"
			(at -0.0254 -3.5433 0)
			(unlocked yes)
			(layer "F.Fab")
			(hide yes)
			(effects
				(font
					(size 1.016 1.016)
					(thickness 0.1524)
				)
			)
		)
		(duplicate_pad_numbers_are_jumpers no)
		(fp_line
			(start -0.2032 0)
			(end -0.4191 0)
			(stroke
				(width 0.2032)
				(type default)
			)
			(layer "F.SilkS")
		)
		(fp_line
			(start 0.4318 0)
			(end 0.2032 0)
			(stroke
				(width 0.2032)
				(type default)
			)
			(layer "F.SilkS")
		)
		(fp_rect
			(start -0.635 1.1811)
			(end 0.635 -1.1811)
			(stroke
				(width 0)
				(type default)
			)
			(fill no)
			(layer "F.CrtYd")
		)
		(fp_rect
			(start -0.635 1.1811)
			(end 0.635 -1.1811)
			(stroke
				(width 0)
				(type default)
			)
			(fill no)
			(layer "F.Fab")
		)
		(pad "1" smd custom
			(at 0 -0.6604)
			(size 0.19685 0.19685)
			(layers "F.Cu" "F.Mask" "F.Paste")
			(net "P3V3_STBY")
			(options
				(clearance outline)
				(anchor circle)
			)
			(primitives
				(gr_poly
					(pts
						(arc
							(start 0.508 -0.2921)
							(mid 0.478242 -0.363942)
							(end 0.4064 -0.3937)
						)
						(arc
							(start -0.4064 -0.3937)
							(mid -0.478242 -0.363942)
							(end -0.508 -0.2921)
						)
						(arc
							(start -0.508 0.2921)
							(mid -0.478242 0.363942)
							(end -0.4064 0.3937)
						)
						(arc
							(start 0.4064 0.3937)
							(mid 0.478242 0.363942)
							(end 0.508 0.2921)
						)
					)
					(width 0)
					(fill yes)
				)
			)
		)
		(pad "2" smd custom
			(at 0 0.6604)
			(size 0.19685 0.19685)
			(layers "F.Cu" "F.Mask" "F.Paste")
			(net "VR_PVIN_P1V0_STBY")
			(options
				(clearance outline)
				(anchor circle)
			)
			(primitives
				(gr_poly
					(pts
						(arc
							(start 0.508 -0.2921)
							(mid 0.478242 -0.363942)
							(end 0.4064 -0.3937)
						)
						(arc
							(start -0.4064 -0.3937)
							(mid -0.478242 -0.363942)
							(end -0.508 -0.2921)
						)
						(arc
							(start -0.508 0.2921)
							(mid -0.478242 0.363942)
							(end -0.4064 0.3937)
						)
						(arc
							(start 0.4064 0.3937)
							(mid 0.478242 0.363942)
							(end 0.508 0.2921)
						)
					)
					(width 0)
					(fill yes)
				)
			)
		)
	)
	(footprint ""
		(layer "F.Cu")
		(at 68.834 -57.7088)
		(property "Reference" "R503"
			(at 0 0 0)
			(layer "F.SilkS")
			(hide yes)
			(effects
				(font
					(size 1.27 1.27)
				)
			)
		)
		(property "Value" "10KR2F-2-GP"
			(at 1.7907 -1.1176 0)
			(unlocked yes)
			(layer "F.Fab")
			(hide yes)
			(effects
				(font
					(size 1.016 1.016)
					(thickness 0.1524)
				)
			)
		)
		(property "Device Type" "R402H16"
			(at 1.7907 -2.6416 0)
			(unlocked yes)
			(layer "F.Fab")
			(hide yes)
			(effects
				(font
					(size 1.016 1.016)
					(thickness 0.1524)
				)
			)
		)
		(duplicate_pad_numbers_are_jumpers no)
		(fp_rect
			(start -0.381 0.8382)
			(end 0.381 -0.8382)
			(stroke
				(width 0)
				(type default)
			)
			(fill no)
			(layer "F.CrtYd")
		)
		(fp_rect
			(start -0.381 0.8382)
			(end 0.381 -0.8382)
			(stroke
				(width 0)
				(type default)
			)
			(fill no)
			(layer "F.Fab")
		)
		(pad "1" smd custom
			(at 0 -0.4318)
			(size 0.127 0.127)
			(layers "F.Cu" "F.Mask" "F.Paste")
			(net "P3V3_SENSE")
			(options
				(clearance outline)
				(anchor circle)
			)
			(primitives
				(gr_poly
					(pts
						(arc
							(start -0.2032 -0.2794)
							(mid -0.239121 -0.264521)
							(end -0.254 -0.2286)
						)
						(arc
							(start -0.254 0.2286)
							(mid -0.239121 0.264521)
							(end -0.2032 0.2794)
						)
						(arc
							(start 0.2032 0.2794)
							(mid 0.239121 0.264521)
							(end 0.254 0.2286)
						)
						(arc
							(start 0.254 -0.2286)
							(mid 0.239121 -0.264521)
							(end 0.2032 -0.2794)
						)
					)
					(width 0)
					(fill yes)
				)
			)
		)
		(pad "2" smd custom
			(at 0 0.4318)
			(size 0.127 0.127)
			(layers "F.Cu" "F.Mask" "F.Paste")
			(net "GND")
			(options
				(clearance outline)
				(anchor circle)
			)
			(primitives
				(gr_poly
					(pts
						(arc
							(start -0.2032 -0.2794)
							(mid -0.239121 -0.264521)
							(end -0.254 -0.2286)
						)
						(arc
							(start -0.254 0.2286)
							(mid -0.239121 0.264521)
							(end -0.2032 0.2794)
						)
						(arc
							(start 0.2032 0.2794)
							(mid 0.239121 0.264521)
							(end 0.254 0.2286)
						)
						(arc
							(start 0.254 -0.2286)
							(mid 0.239121 -0.264521)
							(end 0.2032 -0.2794)
						)
					)
					(width 0)
					(fill yes)
				)
			)
		)
	)
	(footprint ""
		(layer "F.Cu")
		(at 19.6596 -50.9524)
		(property "Reference" "PR94"
			(at 0 0 0)
			(layer "F.SilkS")
			(hide yes)
			(effects
				(font
					(size 1.27 1.27)
				)
			)
		)
		(property "Value" "100R3F-1-GP"
			(at -0.0254 -2.0193 0)
			(unlocked yes)
			(layer "F.Fab")
			(hide yes)
			(effects
				(font
					(size 1.016 1.016)
					(thickness 0.1524)
				)
			)
		)
		(property "Device Type" "R603H22"
			(at -0.0254 -3.5433 0)
			(unlocked yes)
			(layer "F.Fab")
			(hide yes)
			(effects
				(font
					(size 1.016 1.016)
					(thickness 0.1524)
				)
			)
		)
		(duplicate_pad_numbers_are_jumpers no)
		(fp_line
			(start -0.2032 0)
			(end -0.4191 0)
			(stroke
				(width 0.2032)
				(type default)
			)
			(layer "F.SilkS")
		)
		(fp_line
			(start 0.4318 0)
			(end 0.2032 0)
			(stroke
				(width 0.2032)
				(type default)
			)
			(layer "F.SilkS")
		)
		(fp_rect
			(start -0.635 1.1811)
			(end 0.635 -1.1811)
			(stroke
				(width 0)
				(type default)
			)
			(fill no)
			(layer "F.CrtYd")
		)
		(fp_rect
			(start -0.635 1.1811)
			(end 0.635 -1.1811)
			(stroke
				(width 0)
				(type default)
			)
			(fill no)
			(layer "F.Fab")
		)
		(pad "1" smd custom
			(at 0 -0.6604)
			(size 0.19685 0.19685)
			(layers "F.Cu" "F.Mask" "F.Paste")
			(net "VR_PVCCP_FB")
			(options
				(clearance outline)
				(anchor circle)
			)
			(primitives
				(gr_poly
					(pts
						(arc
							(start 0.508 -0.2921)
							(mid 0.478242 -0.363942)
							(end 0.4064 -0.3937)
						)
						(arc
							(start -0.4064 -0.3937)
							(mid -0.478242 -0.363942)
							(end -0.508 -0.2921)
						)
						(arc
							(start -0.508 0.2921)
							(mid -0.478242 0.363942)
							(end -0.4064 0.3937)
						)
						(arc
							(start 0.4064 0.3937)
							(mid 0.478242 0.363942)
							(end 0.508 0.2921)
						)
					)
					(width 0)
					(fill yes)
				)
			)
		)
		(pad "2" smd custom
			(at 0 0.6604)
			(size 0.19685 0.19685)
			(layers "F.Cu" "F.Mask" "F.Paste")
			(net "VR_PVCCP_FB_RC1")
			(options
				(clearance outline)
				(anchor circle)
			)
			(primitives
				(gr_poly
					(pts
						(arc
							(start 0.508 -0.2921)
							(mid 0.478242 -0.363942)
							(end 0.4064 -0.3937)
						)
						(arc
							(start -0.4064 -0.3937)
							(mid -0.478242 -0.363942)
							(end -0.508 -0.2921)
						)
						(arc
							(start -0.508 0.2921)
							(mid -0.478242 0.363942)
							(end -0.4064 0.3937)
						)
						(arc
							(start 0.4064 0.3937)
							(mid 0.478242 0.363942)
							(end 0.508 0.2921)
						)
					)
					(width 0)
					(fill yes)
				)
			)
		)
	)
	(footprint ""
		(layer "F.Cu")
		(at 157.353 -59.309)
		(property "Reference" "C327"
			(at 0 0 0)
			(layer "F.SilkS")
			(hide yes)
			(effects
				(font
					(size 1.27 1.27)
				)
			)
		)
		(property "Value" "SCD1U16V2KX-3GP"
			(at 1.8923 -1.2065 0)
			(unlocked yes)
			(layer "F.Fab")
			(hide yes)
			(effects
				(font
					(size 1.016 1.016)
					(thickness 0.1524)
				)
			)
		)
		(property "Device Type" "C402H22"
			(at 1.8923 -2.7305 0)
			(unlocked yes)
			(layer "F.Fab")
			(hide yes)
			(effects
				(font
					(size 1.016 1.016)
					(thickness 0.1524)
				)
			)
		)
		(duplicate_pad_numbers_are_jumpers no)
		(fp_rect
			(start -0.381 0.7366)
			(end 0.381 -0.7366)
			(stroke
				(width 0)
				(type default)
			)
			(fill no)
			(layer "F.CrtYd")
		)
		(fp_rect
			(start -0.381 0.7366)
			(end 0.381 -0.7366)
			(stroke
				(width 0)
				(type default)
			)
			(fill no)
			(layer "F.Fab")
		)
		(pad "1" smd custom
			(at 0 -0.4572)
			(size 0.1143 0.1143)
			(layers "F.Cu" "F.Mask" "F.Paste")
			(net "PV_VDDR")
			(options
				(clearance outline)
				(anchor circle)
			)
			(primitives
				(gr_poly
					(pts
						(arc
							(start -0.254 -0.1778)
							(mid -0.239121 -0.213721)
							(end -0.2032 -0.2286)
						)
						(arc
							(start 0.2032 -0.2286)
							(mid 0.239121 -0.213721)
							(end 0.254 -0.1778)
						)
						(arc
							(start 0.254 0.1778)
							(mid 0.239121 0.213721)
							(end 0.2032 0.2286)
						)
						(arc
							(start -0.2032 0.2286)
							(mid -0.239121 0.213721)
							(end -0.254 0.1778)
						)
					)
					(width 0)
					(fill yes)
				)
			)
		)
		(pad "2" smd custom
			(at 0 0.4572)
			(size 0.1143 0.1143)
			(layers "F.Cu" "F.Mask" "F.Paste")
			(net "GND")
			(options
				(clearance outline)
				(anchor circle)
			)
			(primitives
				(gr_poly
					(pts
						(arc
							(start -0.254 -0.1778)
							(mid -0.239121 -0.213721)
							(end -0.2032 -0.2286)
						)
						(arc
							(start 0.2032 -0.2286)
							(mid 0.239121 -0.213721)
							(end 0.254 -0.1778)
						)
						(arc
							(start 0.254 0.1778)
							(mid 0.239121 0.213721)
							(end 0.2032 0.2286)
						)
						(arc
							(start -0.2032 0.2286)
							(mid -0.239121 0.213721)
							(end -0.254 0.1778)
						)
					)
					(width 0)
					(fill yes)
				)
			)
		)
	)
	(footprint ""
		(layer "F.Cu")
		(at 169.545 -42.291 180)
		(property "Reference" "PR228"
			(at 0 0 180)
			(layer "F.SilkS")
			(hide yes)
			(effects
				(font
					(size 1.27 1.27)
				)
			)
		)
		(property "Value" "30K1R2F-L-GP"
			(at 1.7907 -1.1176 180)
			(unlocked yes)
			(layer "F.Fab")
			(hide yes)
			(effects
				(font
					(size 1.016 1.016)
					(thickness 0.1524)
				)
			)
		)
		(property "Device Type" "R402H16"
			(at 1.7907 -2.6416 180)
			(unlocked yes)
			(layer "F.Fab")
			(hide yes)
			(effects
				(font
					(size 1.016 1.016)
					(thickness 0.1524)
				)
			)
		)
		(duplicate_pad_numbers_are_jumpers no)
		(fp_rect
			(start -0.381 0.8382)
			(end 0.381 -0.8382)
			(stroke
				(width 0)
				(type default)
			)
			(fill no)
			(layer "F.CrtYd")
		)
		(fp_rect
			(start -0.381 0.8382)
			(end 0.381 -0.8382)
			(stroke
				(width 0)
				(type default)
			)
			(fill no)
			(layer "F.Fab")
		)
		(pad "1" smd custom
			(at 0 -0.4318 180)
			(size 0.127 0.127)
			(layers "F.Cu" "F.Mask" "F.Paste")
			(net "P2V5_STBY_FB")
			(options
				(clearance outline)
				(anchor circle)
			)
			(primitives
				(gr_poly
					(pts
						(arc
							(start -0.2032 -0.2794)
							(mid -0.239121 -0.264521)
							(end -0.254 -0.2286)
						)
						(arc
							(start -0.254 0.2286)
							(mid -0.239121 0.264521)
							(end -0.2032 0.2794)
						)
						(arc
							(start 0.2032 0.2794)
							(mid 0.239121 0.264521)
							(end 0.254 0.2286)
						)
						(arc
							(start 0.254 -0.2286)
							(mid 0.239121 -0.264521)
							(end 0.2032 -0.2794)
						)
					)
					(width 0)
					(fill yes)
				)
			)
		)
		(pad "2" smd custom
			(at 0 0.4318 180)
			(size 0.127 0.127)
			(layers "F.Cu" "F.Mask" "F.Paste")
			(net "GND")
			(options
				(clearance outline)
				(anchor circle)
			)
			(primitives
				(gr_poly
					(pts
						(arc
							(start -0.2032 -0.2794)
							(mid -0.239121 -0.264521)
							(end -0.254 -0.2286)
						)
						(arc
							(start -0.254 0.2286)
							(mid -0.239121 0.264521)
							(end -0.2032 0.2794)
						)
						(arc
							(start 0.2032 0.2794)
							(mid 0.239121 0.264521)
							(end 0.254 0.2286)
						)
						(arc
							(start 0.254 -0.2286)
							(mid 0.239121 -0.264521)
							(end 0.2032 -0.2794)
						)
					)
					(width 0)
					(fill yes)
				)
			)
		)
	)
)
